# T6G (Grand Teton) — schematic netlist excerpt (pin names and nets, part order shuffled) for the footprints in the layout excerpt that follows; sources: Cadence DE-HDL packaged netlist, KiCad conversion of 04192023_DAF0TMB3IC0_F0TG_MB_C_brd_V02_OCP.brd

R3594  Q_RES  33.2 1% CHIP  pkg 0402LF  page 251 : A = SMB_INA230_3V3AUX_SCL ; B = SMB_INA230_4_3V3AUX_SCL_R
C925  Q_CAP_DIFFBUS  DIFF BUS_0.22UF 6.3V 20% X6S  pkg C0201  page 63 : \1\ = P5E_CPU0_P0_TX_C_DP<4> ; \2\ = P5E_CPU0_P0_TX_DP<4>
C1332  Q_CAP  100NF 50V 10% X7R  pkg C0402  page 188 : A = P3V3_AUX ; B = GND

(kicad_pcb
	(version 20260206)
	(generator "pcbnew")
	(generator_version "10.0")
	(general
		(thickness 1.6)
		(legacy_teardrops no)
	)
	(paper "A4")
	(title_block
		(title "04192023_DAF0TMB3IC0_F0TG_MB_C_brd_V02_OCP.brd")
		(comment 1 "Grand Teton / footprints 4642-4644 of 8354")
	)
	(layers
		(0 "F.Cu" signal "TOP")
		(4 "In1.Cu" signal "GND")
		(6 "In2.Cu" signal "IN1")
		(8 "In3.Cu" signal "GND1")
		(10 "In4.Cu" signal "IN2")
		(12 "In5.Cu" signal "GND2")
		(14 "In6.Cu" signal "IN3")
		(16 "In7.Cu" signal "GND3")
		(18 "In8.Cu" signal "VCC")
		(20 "In9.Cu" signal "VCC1")
		(22 "In10.Cu" signal "GND4")
		(24 "In11.Cu" signal "IN4")
		(26 "In12.Cu" signal "GND5")
		(28 "In13.Cu" signal "IN5")
		(30 "In14.Cu" signal "GND6")
		(32 "In15.Cu" signal "IN6")
		(34 "In16.Cu" signal "GND7")
		(2 "B.Cu" signal "BOTTOM")
		(9 "F.Adhes" user "F.Adhesive")
		(11 "B.Adhes" user "B.Adhesive")
		(13 "F.Paste" user "Package Geometry/Pastemask Top")
		(15 "B.Paste" user "Package Geometry/Pastemask Bottom")
		(5 "F.SilkS" user "Ref Des/Silkscreen Top")
		(7 "B.SilkS" user "Ref Des/Silkscreen Bottom")
		(1 "F.Mask" user "Board Geometry/Soldermask Top")
		(3 "B.Mask" user "Board Geometry/Soldermask Bottom")
		(17 "Dwgs.User" user "User.Drawings")
		(19 "Cmts.User" user "User.Comments")
		(21 "Eco1.User" user "User.Eco1")
		(23 "Eco2.User" user "User.Eco2")
		(25 "Edge.Cuts" user "Board Geometry/Outline")
		(27 "Margin" user)
		(31 "F.CrtYd" user "Package Geometry/Place Bound Top")
		(29 "B.CrtYd" user "Package Geometry/Place Bound Bottom")
		(35 "F.Fab" user "Ref Des/Assembly Top")
		(33 "B.Fab" user "Ref Des/Assembly Bottom")
	)
	(footprint ""
		(layer "F.Cu")
		(at 445.003682 -65.947798 -90)
		(property "Reference" "C1332"
			(at 0 0 270)
			(layer "F.SilkS")
			(hide yes)
			(effects
				(font
					(size 1.27 1.27)
				)
			)
		)
		(property "Value" ""
			(at 0 0 270)
			(layer "F.Fab")
			(effects
				(font
					(size 1.27 1.27)
				)
			)
		)
		(duplicate_pad_numbers_are_jumpers no)
		(fp_line
			(start -0.7874 0.4064)
			(end -0.7874 -0.4064)
			(stroke
				(width 0.1524)
				(type default)
			)
			(layer "F.SilkS")
		)
		(fp_line
			(start 0.7874 0.4064)
			(end -0.7874 0.4064)
			(stroke
				(width 0.1524)
				(type default)
			)
			(layer "F.SilkS")
		)
		(fp_line
			(start -0.7874 -0.4064)
			(end 0.7874 -0.4064)
			(stroke
				(width 0.1524)
				(type default)
			)
			(layer "F.SilkS")
		)
		(fp_line
			(start 0.7874 -0.4064)
			(end 0.7874 0.4064)
			(stroke
				(width 0.1524)
				(type default)
			)
			(layer "F.SilkS")
		)
		(fp_line
			(start -0.67945 0.3048)
			(end -0.67945 -0.305054)
			(stroke
				(width 0.1)
				(type default)
			)
			(layer "F.Fab")
		)
		(fp_line
			(start -0.12065 0.3048)
			(end -0.67945 0.3048)
			(stroke
				(width 0.1)
				(type default)
			)
			(layer "F.Fab")
		)
		(fp_line
			(start 0.120396 0.3048)
			(end 0.120396 0.2794)
			(stroke
				(width 0.1)
				(type default)
			)
			(layer "F.Fab")
		)
		(fp_line
			(start 0.67945 0.3048)
			(end 0.120396 0.3048)
			(stroke
				(width 0.1)
				(type default)
			)
			(layer "F.Fab")
		)
		(fp_line
			(start -0.12065 0.2794)
			(end -0.12065 0.3048)
			(stroke
				(width 0.1)
				(type default)
			)
			(layer "F.Fab")
		)
		(fp_line
			(start 0.120396 0.2794)
			(end -0.12065 0.2794)
			(stroke
				(width 0.1)
				(type default)
			)
			(layer "F.Fab")
		)
		(fp_line
			(start -0.12065 -0.2794)
			(end 0.12065 -0.2794)
			(stroke
				(width 0.1)
				(type default)
			)
			(layer "F.Fab")
		)
		(fp_line
			(start 0.12065 -0.2794)
			(end 0.12065 -0.3048)
			(stroke
				(width 0.1)
				(type default)
			)
			(layer "F.Fab")
		)
		(fp_line
			(start 0.12065 -0.3048)
			(end 0.67945 -0.3048)
			(stroke
				(width 0.1)
				(type default)
			)
			(layer "F.Fab")
		)
		(fp_line
			(start 0.67945 -0.3048)
			(end 0.67945 0.3048)
			(stroke
				(width 0.1)
				(type default)
			)
			(layer "F.Fab")
		)
		(fp_line
			(start -0.67945 -0.305054)
			(end -0.12065 -0.305054)
			(stroke
				(width 0.1)
				(type default)
			)
			(layer "F.Fab")
		)
		(fp_line
			(start -0.12065 -0.305054)
			(end -0.12065 -0.2794)
			(stroke
				(width 0.1)
				(type default)
			)
			(layer "F.Fab")
		)
		(pad "1" smd circle
			(at -0.40005 0 270)
			(size 0 0)
			(layers "F.Cu" "F.Mask" "F.Paste")
			(net "P3V3_AUX")
		)
		(pad "2" smd circle
			(at 0.40005 0 270)
			(size 0 0)
			(layers "F.Cu" "F.Mask" "F.Paste")
			(net "GND")
		)
	)
	(footprint ""
		(layer "F.Cu")
		(at 154.633676 -50.739294 90)
		(property "Reference" "R3594"
			(at 0 0 90)
			(layer "F.SilkS")
			(hide yes)
			(effects
				(font
					(size 1.27 1.27)
				)
			)
		)
		(property "Value" ""
			(at 0 0 90)
			(layer "F.Fab")
			(effects
				(font
					(size 1.27 1.27)
				)
			)
		)
		(duplicate_pad_numbers_are_jumpers no)
		(fp_line
			(start 0.7874 -0.4064)
			(end 0.7874 0.4064)
			(stroke
				(width 0.1524)
				(type default)
			)
			(layer "F.SilkS")
		)
		(fp_line
			(start -0.7874 -0.4064)
			(end 0.7874 -0.4064)
			(stroke
				(width 0.1524)
				(type default)
			)
			(layer "F.SilkS")
		)
		(fp_line
			(start 0.7874 0.4064)
			(end -0.7874 0.4064)
			(stroke
				(width 0.1524)
				(type default)
			)
			(layer "F.SilkS")
		)
		(fp_line
			(start -0.7874 0.4064)
			(end -0.7874 -0.4064)
			(stroke
				(width 0.1524)
				(type default)
			)
			(layer "F.SilkS")
		)
		(fp_line
			(start -0.12065 -0.305054)
			(end -0.12065 -0.2794)
			(stroke
				(width 0.1)
				(type default)
			)
			(layer "F.Fab")
		)
		(fp_line
			(start -0.67945 -0.305054)
			(end -0.12065 -0.305054)
			(stroke
				(width 0.1)
				(type default)
			)
			(layer "F.Fab")
		)
		(fp_line
			(start 0.67945 -0.3048)
			(end 0.67945 0.3048)
			(stroke
				(width 0.1)
				(type default)
			)
			(layer "F.Fab")
		)
		(fp_line
			(start 0.12065 -0.3048)
			(end 0.67945 -0.3048)
			(stroke
				(width 0.1)
				(type default)
			)
			(layer "F.Fab")
		)
		(fp_line
			(start 0.12065 -0.2794)
			(end 0.12065 -0.3048)
			(stroke
				(width 0.1)
				(type default)
			)
			(layer "F.Fab")
		)
		(fp_line
			(start -0.12065 -0.2794)
			(end 0.12065 -0.2794)
			(stroke
				(width 0.1)
				(type default)
			)
			(layer "F.Fab")
		)
		(fp_line
			(start 0.120396 0.2794)
			(end -0.12065 0.2794)
			(stroke
				(width 0.1)
				(type default)
			)
			(layer "F.Fab")
		)
		(fp_line
			(start -0.12065 0.2794)
			(end -0.12065 0.3048)
			(stroke
				(width 0.1)
				(type default)
			)
			(layer "F.Fab")
		)
		(fp_line
			(start 0.67945 0.3048)
			(end 0.120396 0.3048)
			(stroke
				(width 0.1)
				(type default)
			)
			(layer "F.Fab")
		)
		(fp_line
			(start 0.120396 0.3048)
			(end 0.120396 0.2794)
			(stroke
				(width 0.1)
				(type default)
			)
			(layer "F.Fab")
		)
		(fp_line
			(start -0.12065 0.3048)
			(end -0.67945 0.3048)
			(stroke
				(width 0.1)
				(type default)
			)
			(layer "F.Fab")
		)
		(fp_line
			(start -0.67945 0.3048)
			(end -0.67945 -0.305054)
			(stroke
				(width 0.1)
				(type default)
			)
			(layer "F.Fab")
		)
		(pad "1" smd circle
			(at -0.40005 0 90)
			(size 0 0)
			(layers "F.Cu" "F.Mask" "F.Paste")
			(net "SMB_INA230_3V3AUX_SCL")
		)
		(pad "2" smd circle
			(at 0.40005 0 90)
			(size 0 0)
			(layers "F.Cu" "F.Mask" "F.Paste")
			(net "SMB_INA230_4_3V3AUX_SCL_R")
		)
	)
	(footprint ""
		(layer "F.Cu")
		(at 304.094896 -383.88163 -90)
		(property "Reference" "C925"
			(at 0 0 270)
			(layer "F.SilkS")
			(hide yes)
			(effects
				(font
					(size 1.27 1.27)
				)
			)
		)
		(property "Value" ""
			(at 0 0 270)
			(layer "F.Fab")
			(effects
				(font
					(size 1.27 1.27)
				)
			)
		)
		(duplicate_pad_numbers_are_jumpers no)
		(fp_line
			(start -0.299974 0.150114)
			(end -0.299974 -0.150114)
			(stroke
				(width 0.1)
				(type default)
			)
			(layer "F.Fab")
		)
		(fp_line
			(start 0.299974 0.150114)
			(end -0.299974 0.150114)
			(stroke
				(width 0.1)
				(type default)
			)
			(layer "F.Fab")
		)
		(fp_line
			(start -0.299974 -0.150114)
			(end 0.299974 -0.150114)
			(stroke
				(width 0.1)
				(type default)
			)
			(layer "F.Fab")
		)
		(fp_line
			(start 0.299974 -0.150114)
			(end 0.299974 0.150114)
			(stroke
				(width 0.1)
				(type default)
			)
			(layer "F.Fab")
		)
		(pad "1" smd rect
			(at -0.2667 0 270)
			(size 0.3048 0.381)
			(layers "F.Cu" "F.Mask" "F.Paste")
			(net "P5E_CPU0_P0_TX_C_DP<4>")
		)
		(pad "2" smd rect
			(at 0.2667 0 270)
			(size 0.3048 0.381)
			(layers "F.Cu" "F.Mask" "F.Paste")
			(net "P5E_CPU0_P0_TX_DP<4>")
		)
	)
)
